(kicad_pcb
	(version 20260206)
	(generator "pcbnew")
	(generator_version "10.0")
	(general
		(thickness 1.6)
		(legacy_teardrops no)
	)
	(paper "A4")
	(title_block
		(title "01162023_DA0F0TEBIF0_F0T_Expander_BD_F_brd_V02_OCP.brd")
		(comment 1 "Grand Teton / footprints 1789-1796 of 9728")
	)
	(layers
		(0 "F.Cu" signal "TOP")
		(4 "In1.Cu" signal "GND")
		(6 "In2.Cu" signal "VCC")
		(8 "In3.Cu" signal "VCC1")
		(10 "In4.Cu" signal "GND1")
		(12 "In5.Cu" signal "IN1")
		(14 "In6.Cu" signal "GND2")
		(16 "In7.Cu" signal "IN2")
		(18 "In8.Cu" signal "GND3")
		(20 "In9.Cu" signal "IN3")
		(22 "In10.Cu" signal "GND4")
		(24 "In11.Cu" signal "IN4")
		(26 "In12.Cu" signal "GND5")
		(28 "In13.Cu" signal "IN5")
		(30 "In14.Cu" signal "GND6")
		(32 "In15.Cu" signal "IN6")
		(34 "In16.Cu" signal "GND7")
		(2 "B.Cu" signal "BOTTOM")
		(9 "F.Adhes" user "F.Adhesive")
		(11 "B.Adhes" user "B.Adhesive")
		(13 "F.Paste" user "Package Geometry/Pastemask Top")
		(15 "B.Paste" user "Package Geometry/Pastemask Bottom")
		(5 "F.SilkS" user "Ref Des/Silkscreen Top")
		(7 "B.SilkS" user "Ref Des/Silkscreen Bottom")
		(1 "F.Mask" user "Board Geometry/Soldermask Top")
		(3 "B.Mask" user "Board Geometry/Soldermask Bottom")
		(17 "Dwgs.User" user "User.Drawings")
		(19 "Cmts.User" user "User.Comments")
		(21 "Eco1.User" user "User.Eco1")
		(23 "Eco2.User" user "User.Eco2")
		(25 "Edge.Cuts" user "Board Geometry/Outline")
		(27 "Margin" user)
		(31 "F.CrtYd" user "Package Geometry/Place Bound Top")
		(29 "B.CrtYd" user "Package Geometry/Place Bound Bottom")
		(35 "F.Fab" user "Ref Des/Assembly Top")
		(33 "B.Fab" user "Ref Des/Assembly Bottom")
	)
	(footprint ""
		(layer "F.Cu")
		(at 371.956584 -17.419574 180)
		(property "Reference" "R1716"
			(at 0 0 180)
			(layer "F.SilkS")
			(hide yes)
			(effects
				(font
					(size 1.27 1.27)
				)
			)
		)
		(property "Value" ""
			(at 0 0 180)
			(layer "F.Fab")
			(effects
				(font
					(size 1.27 1.27)
				)
			)
		)
		(duplicate_pad_numbers_are_jumpers no)
		(fp_line
			(start 0.7874 0.4064)
			(end -0.7874 0.4064)
			(stroke
				(width 0.1524)
				(type default)
			)
			(layer "F.SilkS")
		)
		(fp_line
			(start 0.7874 -0.4064)
			(end 0.7874 0.4064)
			(stroke
				(width 0.1524)
				(type default)
			)
			(layer "F.SilkS")
		)
		(fp_line
			(start -0.7874 0.4064)
			(end -0.7874 -0.4064)
			(stroke
				(width 0.1524)
				(type default)
			)
			(layer "F.SilkS")
		)
		(fp_line
			(start -0.7874 -0.4064)
			(end 0.7874 -0.4064)
			(stroke
				(width 0.1524)
				(type default)
			)
			(layer "F.SilkS")
		)
		(fp_line
			(start 0.67945 0.3048)
			(end 0.120396 0.3048)
			(stroke
				(width 0.1)
				(type default)
			)
			(layer "F.Fab")
		)
		(fp_line
			(start 0.67945 -0.3048)
			(end 0.67945 0.3048)
			(stroke
				(width 0.1)
				(type default)
			)
			(layer "F.Fab")
		)
		(fp_line
			(start 0.12065 -0.2794)
			(end 0.12065 -0.3048)
			(stroke
				(width 0.1)
				(type default)
			)
			(layer "F.Fab")
		)
		(fp_line
			(start 0.12065 -0.3048)
			(end 0.67945 -0.3048)
			(stroke
				(width 0.1)
				(type default)
			)
			(layer "F.Fab")
		)
		(fp_line
			(start 0.120396 0.3048)
			(end 0.120396 0.2794)
			(stroke
				(width 0.1)
				(type default)
			)
			(layer "F.Fab")
		)
		(fp_line
			(start 0.120396 0.2794)
			(end -0.12065 0.2794)
			(stroke
				(width 0.1)
				(type default)
			)
			(layer "F.Fab")
		)
		(fp_line
			(start -0.12065 0.3048)
			(end -0.67945 0.3048)
			(stroke
				(width 0.1)
				(type default)
			)
			(layer "F.Fab")
		)
		(fp_line
			(start -0.12065 0.2794)
			(end -0.12065 0.3048)
			(stroke
				(width 0.1)
				(type default)
			)
			(layer "F.Fab")
		)
		(fp_line
			(start -0.12065 -0.2794)
			(end 0.12065 -0.2794)
			(stroke
				(width 0.1)
				(type default)
			)
			(layer "F.Fab")
		)
		(fp_line
			(start -0.12065 -0.305054)
			(end -0.12065 -0.2794)
			(stroke
				(width 0.1)
				(type default)
			)
			(layer "F.Fab")
		)
		(fp_line
			(start -0.67945 0.3048)
			(end -0.67945 -0.305054)
			(stroke
				(width 0.1)
				(type default)
			)
			(layer "F.Fab")
		)
		(fp_line
			(start -0.67945 -0.305054)
			(end -0.12065 -0.305054)
			(stroke
				(width 0.1)
				(type default)
			)
			(layer "F.Fab")
		)
		(pad "1" smd circle
			(at -0.40005 0 180)
			(size 0 0)
			(layers "F.Cu" "F.Mask" "F.Paste")
			(net "P3V3_SSD12")
		)
		(pad "2" smd circle
			(at 0.40005 0 180)
			(size 0 0)
			(layers "F.Cu" "F.Mask" "F.Paste")
			(net "SMB_ISO_SSD12_SCL")
		)
	)
	(footprint ""
		(layer "F.Cu")
		(at 20.399756 -174.271178 180)
		(property "Reference" "R501"
			(at 0 0 180)
			(layer "F.SilkS")
			(hide yes)
			(effects
				(font
					(size 1.27 1.27)
				)
			)
		)
		(property "Value" ""
			(at 0 0 180)
			(layer "F.Fab")
			(effects
				(font
					(size 1.27 1.27)
				)
			)
		)
		(duplicate_pad_numbers_are_jumpers no)
		(fp_line
			(start 0.7874 0.4064)
			(end -0.7874 0.4064)
			(stroke
				(width 0.1524)
				(type default)
			)
			(layer "F.SilkS")
		)
		(fp_line
			(start 0.7874 -0.4064)
			(end 0.7874 0.4064)
			(stroke
				(width 0.1524)
				(type default)
			)
			(layer "F.SilkS")
		)
		(fp_line
			(start -0.7874 0.4064)
			(end -0.7874 -0.4064)
			(stroke
				(width 0.1524)
				(type default)
			)
			(layer "F.SilkS")
		)
		(fp_line
			(start -0.7874 -0.4064)
			(end 0.7874 -0.4064)
			(stroke
				(width 0.1524)
				(type default)
			)
			(layer "F.SilkS")
		)
		(fp_line
			(start 0.67945 0.3048)
			(end 0.120396 0.3048)
			(stroke
				(width 0.1)
				(type default)
			)
			(layer "F.Fab")
		)
		(fp_line
			(start 0.67945 -0.3048)
			(end 0.67945 0.3048)
			(stroke
				(width 0.1)
				(type default)
			)
			(layer "F.Fab")
		)
		(fp_line
			(start 0.12065 -0.2794)
			(end 0.12065 -0.3048)
			(stroke
				(width 0.1)
				(type default)
			)
			(layer "F.Fab")
		)
		(fp_line
			(start 0.12065 -0.3048)
			(end 0.67945 -0.3048)
			(stroke
				(width 0.1)
				(type default)
			)
			(layer "F.Fab")
		)
		(fp_line
			(start 0.120396 0.3048)
			(end 0.120396 0.2794)
			(stroke
				(width 0.1)
				(type default)
			)
			(layer "F.Fab")
		)
		(fp_line
			(start 0.120396 0.2794)
			(end -0.12065 0.2794)
			(stroke
				(width 0.1)
				(type default)
			)
			(layer "F.Fab")
		)
		(fp_line
			(start -0.12065 0.3048)
			(end -0.67945 0.3048)
			(stroke
				(width 0.1)
				(type default)
			)
			(layer "F.Fab")
		)
		(fp_line
			(start -0.12065 0.2794)
			(end -0.12065 0.3048)
			(stroke
				(width 0.1)
				(type default)
			)
			(layer "F.Fab")
		)
		(fp_line
			(start -0.12065 -0.2794)
			(end 0.12065 -0.2794)
			(stroke
				(width 0.1)
				(type default)
			)
			(layer "F.Fab")
		)
		(fp_line
			(start -0.12065 -0.305054)
			(end -0.12065 -0.2794)
			(stroke
				(width 0.1)
				(type default)
			)
			(layer "F.Fab")
		)
		(fp_line
			(start -0.67945 0.3048)
			(end -0.67945 -0.305054)
			(stroke
				(width 0.1)
				(type default)
			)
			(layer "F.Fab")
		)
		(fp_line
			(start -0.67945 -0.305054)
			(end -0.12065 -0.305054)
			(stroke
				(width 0.1)
				(type default)
			)
			(layer "F.Fab")
		)
		(pad "1" smd circle
			(at -0.40005 0 180)
			(size 0 0)
			(layers "F.Cu" "F.Mask" "F.Paste")
			(net "P5V_AUX")
		)
		(pad "2" smd circle
			(at 0.40005 0 180)
			(size 0 0)
			(layers "F.Cu" "F.Mask" "F.Paste")
			(net "PWRGD_P5V_AUX")
		)
	)
	(footprint ""
		(layer "F.Cu")
		(at 135.626856 -55.418228 90)
		(property "Reference" "PC358"
			(at 0 0 90)
			(layer "F.SilkS")
			(hide yes)
			(effects
				(font
					(size 1.27 1.27)
				)
			)
		)
		(property "Value" ""
			(at 0 0 90)
			(layer "F.Fab")
			(effects
				(font
					(size 1.27 1.27)
				)
			)
		)
		(duplicate_pad_numbers_are_jumpers no)
		(fp_line
			(start 0.7874 -0.4064)
			(end 0.7874 0.4064)
			(stroke
				(width 0.1524)
				(type default)
			)
			(layer "F.SilkS")
		)
		(fp_line
			(start -0.7874 -0.4064)
			(end 0.7874 -0.4064)
			(stroke
				(width 0.1524)
				(type default)
			)
			(layer "F.SilkS")
		)
		(fp_line
			(start 0.7874 0.4064)
			(end -0.7874 0.4064)
			(stroke
				(width 0.1524)
				(type default)
			)
			(layer "F.SilkS")
		)
		(fp_line
			(start -0.7874 0.4064)
			(end -0.7874 -0.4064)
			(stroke
				(width 0.1524)
				(type default)
			)
			(layer "F.SilkS")
		)
		(fp_line
			(start -0.12065 -0.305054)
			(end -0.12065 -0.2794)
			(stroke
				(width 0.1)
				(type default)
			)
			(layer "F.Fab")
		)
		(fp_line
			(start -0.67945 -0.305054)
			(end -0.12065 -0.305054)
			(stroke
				(width 0.1)
				(type default)
			)
			(layer "F.Fab")
		)
		(fp_line
			(start 0.67945 -0.3048)
			(end 0.67945 0.3048)
			(stroke
				(width 0.1)
				(type default)
			)
			(layer "F.Fab")
		)
		(fp_line
			(start 0.12065 -0.3048)
			(end 0.67945 -0.3048)
			(stroke
				(width 0.1)
				(type default)
			)
			(layer "F.Fab")
		)
		(fp_line
			(start 0.12065 -0.2794)
			(end 0.12065 -0.3048)
			(stroke
				(width 0.1)
				(type default)
			)
			(layer "F.Fab")
		)
		(fp_line
			(start -0.12065 -0.2794)
			(end 0.12065 -0.2794)
			(stroke
				(width 0.1)
				(type default)
			)
			(layer "F.Fab")
		)
		(fp_line
			(start 0.120396 0.2794)
			(end -0.12065 0.2794)
			(stroke
				(width 0.1)
				(type default)
			)
			(layer "F.Fab")
		)
		(fp_line
			(start -0.12065 0.2794)
			(end -0.12065 0.3048)
			(stroke
				(width 0.1)
				(type default)
			)
			(layer "F.Fab")
		)
		(fp_line
			(start 0.67945 0.3048)
			(end 0.120396 0.3048)
			(stroke
				(width 0.1)
				(type default)
			)
			(layer "F.Fab")
		)
		(fp_line
			(start 0.120396 0.3048)
			(end 0.120396 0.2794)
			(stroke
				(width 0.1)
				(type default)
			)
			(layer "F.Fab")
		)
		(fp_line
			(start -0.12065 0.3048)
			(end -0.67945 0.3048)
			(stroke
				(width 0.1)
				(type default)
			)
			(layer "F.Fab")
		)
		(fp_line
			(start -0.67945 0.3048)
			(end -0.67945 -0.305054)
			(stroke
				(width 0.1)
				(type default)
			)
			(layer "F.Fab")
		)
		(pad "1" smd circle
			(at -0.40005 0 90)
			(size 0 0)
			(layers "F.Cu" "F.Mask" "F.Paste")
			(net "P12V_SSD4_R")
		)
		(pad "2" smd circle
			(at 0.40005 0 90)
			(size 0 0)
			(layers "F.Cu" "F.Mask" "F.Paste")
			(net "GND")
		)
	)
	(footprint ""
		(layer "F.Cu")
		(at 339.229192 -105.253536)
		(property "Reference" "PD97"
			(at 1.130808 2.791206 0)
			(unlocked yes)
			(layer "F.SilkS")
			(effects
				(font
					(size 0.7874 0.5842)
					(thickness 0.1524)
				)
				(justify left)
			)
		)
		(property "Value" ""
			(at 0 0 0)
			(layer "F.Fab")
			(effects
				(font
					(size 1.27 1.27)
				)
			)
		)
		(duplicate_pad_numbers_are_jumpers no)
		(fp_line
			(start -3.656584 -1.970024)
			(end -3.656584 1.970024)
			(stroke
				(width 0.1524)
				(type default)
			)
			(layer "F.SilkS")
		)
		(fp_line
			(start -3.656584 1.970024)
			(end 4.240784 1.970024)
			(stroke
				(width 0.1524)
				(type default)
			)
			(layer "F.SilkS")
		)
		(fp_line
			(start 4.240784 -1.970024)
			(end -3.656584 -1.970024)
			(stroke
				(width 0.1524)
				(type default)
			)
			(layer "F.SilkS")
		)
		(fp_line
			(start 4.240784 1.970024)
			(end 4.240784 -1.970024)
			(stroke
				(width 0.1524)
				(type default)
			)
			(layer "F.SilkS")
		)
		(fp_rect
			(start 3.580384 1.970024)
			(end 4.240784 -1.970024)
			(stroke
				(width 0)
				(type default)
			)
			(fill yes)
			(layer "F.SilkS")
		)
		(fp_line
			(start -2.3749 -1.970024)
			(end -2.3749 1.970024)
			(stroke
				(width 0.1)
				(type default)
			)
			(layer "F.Fab")
		)
		(fp_line
			(start -2.3749 1.970024)
			(end 2.3749 1.970024)
			(stroke
				(width 0.1)
				(type default)
			)
			(layer "F.Fab")
		)
		(fp_line
			(start 2.3749 -1.970024)
			(end -2.3749 -1.970024)
			(stroke
				(width 0.1)
				(type default)
			)
			(layer "F.Fab")
		)
		(fp_line
			(start 2.3749 1.970024)
			(end 2.3749 -1.970024)
			(stroke
				(width 0.1)
				(type default)
			)
			(layer "F.Fab")
		)
		(fp_text user "+"
			(at -4.9784 -0.23495 0)
			(unlocked yes)
			(layer "F.Fab")
			(effects
				(font
					(size 1.905 1.4224)
					(thickness 0.1524)
				)
				(justify left)
			)
		)
		(fp_text user "-"
			(at 4.1656 -0.23495 0)
			(unlocked yes)
			(layer "F.Fab")
			(effects
				(font
					(size 1.905 1.4224)
					(thickness 0.1524)
				)
				(justify left)
			)
		)
		(pad "A" smd rect
			(at -2.450084 0)
			(size 2.159 2.2606)
			(layers "F.Cu" "F.Mask" "F.Paste")
			(net "GND")
		)
		(pad "C" smd rect
			(at 2.450084 0)
			(size 2.159 2.2606)
			(layers "F.Cu" "F.Mask" "F.Paste")
			(net "P12V_AUX")
		)
	)
	(footprint ""
		(layer "F.Cu")
		(at 352.920554 -88.359234)
		(property "Reference" "R1617"
			(at 0 0 0)
			(layer "F.SilkS")
			(hide yes)
			(effects
				(font
					(size 1.27 1.27)
				)
			)
		)
		(property "Value" ""
			(at 0 0 0)
			(layer "F.Fab")
			(effects
				(font
					(size 1.27 1.27)
				)
			)
		)
		(duplicate_pad_numbers_are_jumpers no)
		(fp_line
			(start -0.7874 -0.4064)
			(end 0.7874 -0.4064)
			(stroke
				(width 0.1524)
				(type default)
			)
			(layer "F.SilkS")
		)
		(fp_line
			(start -0.7874 0.4064)
			(end -0.7874 -0.4064)
			(stroke
				(width 0.1524)
				(type default)
			)
			(layer "F.SilkS")
		)
		(fp_line
			(start 0.7874 -0.4064)
			(end 0.7874 0.4064)
			(stroke
				(width 0.1524)
				(type default)
			)
			(layer "F.SilkS")
		)
		(fp_line
			(start 0.7874 0.4064)
			(end -0.7874 0.4064)
			(stroke
				(width 0.1524)
				(type default)
			)
			(layer "F.SilkS")
		)
		(fp_line
			(start -0.67945 -0.305054)
			(end -0.12065 -0.305054)
			(stroke
				(width 0.1)
				(type default)
			)
			(layer "F.Fab")
		)
		(fp_line
			(start -0.67945 0.3048)
			(end -0.67945 -0.305054)
			(stroke
				(width 0.1)
				(type default)
			)
			(layer "F.Fab")
		)
		(fp_line
			(start -0.12065 -0.305054)
			(end -0.12065 -0.2794)
			(stroke
				(width 0.1)
				(type default)
			)
			(layer "F.Fab")
		)
		(fp_line
			(start -0.12065 -0.2794)
			(end 0.12065 -0.2794)
			(stroke
				(width 0.1)
				(type default)
			)
			(layer "F.Fab")
		)
		(fp_line
			(start -0.12065 0.2794)
			(end -0.12065 0.3048)
			(stroke
				(width 0.1)
				(type default)
			)
			(layer "F.Fab")
		)
		(fp_line
			(start -0.12065 0.3048)
			(end -0.67945 0.3048)
			(stroke
				(width 0.1)
				(type default)
			)
			(layer "F.Fab")
		)
		(fp_line
			(start 0.120396 0.2794)
			(end -0.12065 0.2794)
			(stroke
				(width 0.1)
				(type default)
			)
			(layer "F.Fab")
		)
		(fp_line
			(start 0.120396 0.3048)
			(end 0.120396 0.2794)
			(stroke
				(width 0.1)
				(type default)
			)
			(layer "F.Fab")
		)
		(fp_line
			(start 0.12065 -0.3048)
			(end 0.67945 -0.3048)
			(stroke
				(width 0.1)
				(type default)
			)
			(layer "F.Fab")
		)
		(fp_line
			(start 0.12065 -0.2794)
			(end 0.12065 -0.3048)
			(stroke
				(width 0.1)
				(type default)
			)
			(layer "F.Fab")
		)
		(fp_line
			(start 0.67945 -0.3048)
			(end 0.67945 0.3048)
			(stroke
				(width 0.1)
				(type default)
			)
			(layer "F.Fab")
		)
		(fp_line
			(start 0.67945 0.3048)
			(end 0.120396 0.3048)
			(stroke
				(width 0.1)
				(type default)
			)
			(layer "F.Fab")
		)
		(pad "1" smd circle
			(at -0.40005 0)
			(size 0 0)
			(layers "F.Cu" "F.Mask" "F.Paste")
			(net "SMB_BIC_I2C9_MUX1_SSD8_R_SCL")
		)
		(pad "2" smd circle
			(at 0.40005 0)
			(size 0 0)
			(layers "F.Cu" "F.Mask" "F.Paste")
			(net "SMB_BIC_I2C9_MUX1_SSD8_SCL")
		)
	)
	(footprint ""
		(layer "F.Cu")
		(at 72.43445 -30.03169 180)
		(property "Reference" "C86"
			(at 0 0 180)
			(layer "F.SilkS")
			(hide yes)
			(effects
				(font
					(size 1.27 1.27)
				)
			)
		)
		(property "Value" ""
			(at 0 0 180)
			(layer "F.Fab")
			(effects
				(font
					(size 1.27 1.27)
				)
			)
		)
		(duplicate_pad_numbers_are_jumpers no)
		(fp_line
			(start 0.299974 0.150114)
			(end -0.299974 0.150114)
			(stroke
				(width 0.1)
				(type default)
			)
			(layer "F.Fab")
		)
		(fp_line
			(start 0.299974 -0.150114)
			(end 0.299974 0.150114)
			(stroke
				(width 0.1)
				(type default)
			)
			(layer "F.Fab")
		)
		(fp_line
			(start -0.299974 0.150114)
			(end -0.299974 -0.150114)
			(stroke
				(width 0.1)
				(type default)
			)
			(layer "F.Fab")
		)
		(fp_line
			(start -0.299974 -0.150114)
			(end 0.299974 -0.150114)
			(stroke
				(width 0.1)
				(type default)
			)
			(layer "F.Fab")
		)
		(pad "1" smd rect
			(at -0.2667 0 180)
			(size 0.3048 0.381)
			(layers "F.Cu" "F.Mask" "F.Paste")
			(net "P5E_PEX0_STN2_TX_DN<37>")
		)
		(pad "2" smd rect
			(at 0.2667 0 180)
			(size 0.3048 0.381)
			(layers "F.Cu" "F.Mask" "F.Paste")
			(net "P5E_PEX0_STN2_TX_C_DN<37>")
		)
	)
	(footprint ""
		(layer "F.Cu")
		(at 82.661506 -136.20115 180)
		(property "Reference" "C17"
			(at 0 0 180)
			(layer "F.SilkS")
			(hide yes)
			(effects
				(font
					(size 1.27 1.27)
				)
			)
		)
		(property "Value" ""
			(at 0 0 180)
			(layer "F.Fab")
			(effects
				(font
					(size 1.27 1.27)
				)
			)
		)
		(duplicate_pad_numbers_are_jumpers no)
		(fp_line
			(start 0.299974 0.150114)
			(end -0.299974 0.150114)
			(stroke
				(width 0.1)
				(type default)
			)
			(layer "F.Fab")
		)
		(fp_line
			(start 0.299974 -0.150114)
			(end 0.299974 0.150114)
			(stroke
				(width 0.1)
				(type default)
			)
			(layer "F.Fab")
		)
		(fp_line
			(start -0.299974 0.150114)
			(end -0.299974 -0.150114)
			(stroke
				(width 0.1)
				(type default)
			)
			(layer "F.Fab")
		)
		(fp_line
			(start -0.299974 -0.150114)
			(end 0.299974 -0.150114)
			(stroke
				(width 0.1)
				(type default)
			)
			(layer "F.Fab")
		)
		(pad "1" smd rect
			(at -0.2667 0 180)
			(size 0.3048 0.381)
			(layers "F.Cu" "F.Mask" "F.Paste")
			(net "P5E_PEX0_STN0_TX_DP<7>")
		)
		(pad "2" smd rect
			(at 0.2667 0 180)
			(size 0.3048 0.381)
			(layers "F.Cu" "F.Mask" "F.Paste")
			(net "P5E_PEX0_STN0_TX_C_DP<7>")
		)
	)
	(footprint ""
		(layer "F.Cu")
		(at 314.861448 -151.596852 180)
		(property "Reference" "C428"
			(at 0 0 180)
			(layer "F.SilkS")
			(hide yes)
			(effects
				(font
					(size 1.27 1.27)
				)
			)
		)
		(property "Value" ""
			(at 0 0 180)
			(layer "F.Fab")
			(effects
				(font
					(size 1.27 1.27)
				)
			)
		)
		(duplicate_pad_numbers_are_jumpers no)
		(fp_line
			(start 0.299974 0.150114)
			(end -0.299974 0.150114)
			(stroke
				(width 0.1)
				(type default)
			)
			(layer "F.Fab")
		)
		(fp_line
			(start 0.299974 -0.150114)
			(end 0.299974 0.150114)
			(stroke
				(width 0.1)
				(type default)
			)
			(layer "F.Fab")
		)
		(fp_line
			(start -0.299974 0.150114)
			(end -0.299974 -0.150114)
			(stroke
				(width 0.1)
				(type default)
			)
			(layer "F.Fab")
		)
		(fp_line
			(start -0.299974 -0.150114)
			(end 0.299974 -0.150114)
			(stroke
				(width 0.1)
				(type default)
			)
			(layer "F.Fab")
		)
		(pad "1" smd rect
			(at -0.2667 0 180)
			(size 0.3048 0.381)
			(layers "F.Cu" "F.Mask" "F.Paste")
			(net "P5E_PEX2_STN0_TX_DN<13>")
		)
		(pad "2" smd rect
			(at 0.2667 0 180)
			(size 0.3048 0.381)
			(layers "F.Cu" "F.Mask" "F.Paste")
			(net "P5E_PEX2_STN0_TX_C_DN<13>")
		)
	)
)
